# T6G (Grand Teton) — schematic parts with pin connectivity, parts 2073–2187 of 8303; source: Cadence DE-HDL packaged netlist (pstxprt.dat, pstxnet.dat, pstchip.dat)

C6080  Q_CAP  0.01UF 50V 10% X7R  pkg C0402  page 177 : 1 = P1V2_AUX ; 2 = GND
C6081  Q_CAP  0.1UF 25V 10% X7R  pkg 0402  page 177 : 1 = P1V2_AUX ; 2 = GND
C6082  Q_CAP  1UF 25V 10% X6S  pkg C0402  page 177 : 1 = P1V2_AUX ; 2 = GND
C6083  Q_CAP  0.1UF 25V 10% X7R  pkg 0402  page 176 : 1 = P3V3_AUX ; 2 = GND
C6084  Q_CAP  0.1UF 25V 10% EMPTY  pkg 0402  page 267 : 1 = U142_VS ; 2 = GND
C6085  Q_CAP  0.1UF 25V 10% EMPTY  pkg 0402  page 270 : 1 = PWRGD_P1V8_AUX_R ; 2 = GND
C6086  Q_CAP  0.1UF 25V 10% X7R  pkg 0402  page 271 : 1 = HSC_TYPE_ADC ; 2 = GND
C6087  Q_CAP  0.1UF 25V 10% X7R  pkg 0402  page 271 : 1 = P3V3_AUX ; 2 = GND
C6088  Q_CAP  10UF 16V 10% X6S  pkg C0805  page 178 : 1 = USB_HUB2_MRP_RESET_N ; 2 = GND
C6089  Q_CAP  1UF 25V 10% X6S  pkg C0402  page 178 : 1 = USB_HUB2_TI_GRSTZ_MRP_PROG_FUNC1 ; 2 = GND
C6090  Q_CAP  27PF 50V 5% NPO  pkg 0402  page 179 : 1 = XTAL_USB_CPU0_HUB2_XOUT ; 2 = GND
C6091  Q_CAP  27PF 50V 5% NPO  pkg 0402  page 179 : 1 = XTAL_USB_CPU0_HUB2_XIN ; 2 = GND
C6092  Q_CAP  1UF 25V 10% X6S  pkg C0402  page 179 : 1 = P3V3_AUX_CPU0_USB2_AVDD33 ; 2 = GND
C6093  Q_CAP  1PF 50V 0.05P COG  pkg C0402  page 179 : 1 = P3V3_AUX_CPU0_USB2_AVDD33 ; 2 = GND
C6094  Q_CAP  0.01UF 50V 10% X7R  pkg C0402  page 179 : 1 = P3V3_AUX_CPU0_USB2_AVDD33 ; 2 = GND
C6095  Q_CAP  0.1UF 25V 10% X7R  pkg 0402  page 179 : 1 = P3V3_AUX_CPU0_USB2_AVDD33 ; 2 = GND
C6096  Q_CAP  1PF 50V 0.05P COG  pkg C0402  page 179 : 1 = P3V3_AUX_CPU0_USB2_AVDD33 ; 2 = GND
C6097  Q_CAP  0.01UF 50V 10% X7R  pkg C0402  page 179 : 1 = P3V3_AUX_CPU0_USB2_AVDD33 ; 2 = GND
C6098  Q_CAP  0.1UF 25V 10% X7R  pkg 0402  page 179 : 1 = P3V3_AUX_CPU0_USB2_AVDD33 ; 2 = GND
C6099  Q_CAP  1PF 50V 0.05P COG  pkg C0402  page 179 : 1 = P3V3_AUX_CPU0_USB2_AVDD33 ; 2 = GND
C6100  Q_CAP  0.01UF 50V 10% X7R  pkg C0402  page 179 : 1 = P3V3_AUX_CPU0_USB2_AVDD33 ; 2 = GND
C6101  Q_CAP  0.1UF 25V 10% X7R  pkg 0402  page 179 : 1 = P3V3_AUX_CPU0_USB2_AVDD33 ; 2 = GND
C6102  Q_CAP  1PF 50V 0.05P COG  pkg C0402  page 179 : 1 = P3V3_AUX_CPU0_USB2_AVDD33 ; 2 = GND
C6103  Q_CAP  0.01UF 50V 10% X7R  pkg C0402  page 179 : 1 = P3V3_AUX_CPU0_USB2_AVDD33 ; 2 = GND
C6104  Q_CAP  0.1UF 25V 10% X7R  pkg 0402  page 179 : 1 = P3V3_AUX_CPU0_USB2_AVDD33 ; 2 = GND
C6105  Q_CAP  10UF 25V 10% X6S  pkg C0805  page 179 : 1 = P1V2_CPU0_USB2_DVDD12 ; 2 = GND
C6106  Q_CAP  1PF 50V 0.05P COG  pkg C0402  page 179 : 1 = P1V2_CPU0_USB2_DVDD12 ; 2 = GND
C6107  Q_CAP  0.01UF 50V 10% X7R  pkg C0402  page 179 : 1 = P1V2_CPU0_USB2_DVDD12 ; 2 = GND
C6108  Q_CAP  0.1UF 25V 10% X7R  pkg 0402  page 179 : 1 = P1V2_CPU0_USB2_DVDD12 ; 2 = GND
C6109  Q_CAP  1PF 50V 0.05P COG  pkg C0402  page 179 : 1 = P1V2_CPU0_USB2_DVDD12 ; 2 = GND
C6110  Q_CAP  0.01UF 50V 10% X7R  pkg C0402  page 179 : 1 = P1V2_CPU0_USB2_DVDD12 ; 2 = GND
C6111  Q_CAP  0.1UF 25V 10% X7R  pkg 0402  page 179 : 1 = P1V2_CPU0_USB2_DVDD12 ; 2 = GND
C6112  Q_CAP  1PF 50V 0.05P COG  pkg C0402  page 179 : 1 = P1V2_CPU0_USB2_DVDD12 ; 2 = GND
C6113  Q_CAP  0.01UF 50V 10% X7R  pkg C0402  page 179 : 1 = P1V2_CPU0_USB2_DVDD12 ; 2 = GND
C6114  Q_CAP  0.1UF 25V 10% X7R  pkg 0402  page 179 : 1 = P1V2_CPU0_USB2_DVDD12 ; 2 = GND
C6115  Q_CAP  1PF 50V 0.05P COG  pkg C0402  page 179 : 1 = P1V2_CPU0_USB2_DVDD12 ; 2 = GND
C6116  Q_CAP  0.01UF 50V 10% X7R  pkg C0402  page 179 : 1 = P1V2_CPU0_USB2_DVDD12 ; 2 = GND
C6117  Q_CAP  0.1UF 25V 10% X7R  pkg 0402  page 179 : 1 = P1V2_CPU0_USB2_DVDD12 ; 2 = GND
C6118  Q_CAP  10UF 25V 10% X6S  pkg C0805  page 179 : 1 = P1V2_CPU0_USB2_DVDD12 ; 2 = GND
C6119  Q_CAP  1PF 50V 0.05P COG  pkg C0402  page 179 : 1 = P1V2_CPU0_USB2_DVDD12 ; 2 = GND
C6120  Q_CAP  0.01UF 50V 10% X7R  pkg C0402  page 179 : 1 = P1V2_CPU0_USB2_DVDD12 ; 2 = GND
C6121  Q_CAP  0.1UF 25V 10% X7R  pkg 0402  page 179 : 1 = P1V2_CPU0_USB2_DVDD12 ; 2 = GND
C6122  Q_CAP  100NF 50V 10% X7R  pkg C0402  page 188 : 1 = P5V ; 2 = GND
C6500  Q_CAP  0.1UF 25V 10% X7R  pkg 0402  page 188 : 1 = P3V3 ; 2 = GND
C6501  Q_CAP_DIFFBUS  DIFF BUS_0.22UF 6.3V 20% X6S  pkg C0201  page 275 : 1 = P5E_CPU0_P0_TX_BUF_C_DP<0> ; 2 = P5E_CPU0_P0_TX_BUF_DP<0>
C6502  Q_CAP_DIFFBUS  DIFF BUS_0.22UF 6.3V 20% X6S  pkg C0201  page 275 : 1 = P5E_CPU0_P0_TX_BUF_C_DN<0> ; 2 = P5E_CPU0_P0_TX_BUF_DN<0>
C6503  Q_CAP_DIFFBUS  DIFF BUS_0.22UF 6.3V 20% X6S  pkg C0201  page 275 : 1 = P5E_CPU0_P0_TX_BUF_C_DP<1> ; 2 = P5E_CPU0_P0_TX_BUF_DP<1>
C6504  Q_CAP_DIFFBUS  DIFF BUS_0.22UF 6.3V 20% X6S  pkg C0201  page 275 : 1 = P5E_CPU0_P0_TX_BUF_C_DN<1> ; 2 = P5E_CPU0_P0_TX_BUF_DN<1>
C6505  Q_CAP_DIFFBUS  DIFF BUS_0.22UF 6.3V 20% X6S  pkg C0201  page 275 : 1 = P5E_CPU0_P0_TX_BUF_C_DP<2> ; 2 = P5E_CPU0_P0_TX_BUF_DP<2>
C6506  Q_CAP_DIFFBUS  DIFF BUS_0.22UF 6.3V 20% X6S  pkg C0201  page 275 : 1 = P5E_CPU0_P0_TX_BUF_C_DN<2> ; 2 = P5E_CPU0_P0_TX_BUF_DN<2>
C6507  Q_CAP_DIFFBUS  DIFF BUS_0.22UF 6.3V 20% X6S  pkg C0201  page 275 : 1 = P5E_CPU0_P0_TX_BUF_C_DP<3> ; 2 = P5E_CPU0_P0_TX_BUF_DP<3>
C6508  Q_CAP_DIFFBUS  DIFF BUS_0.22UF 6.3V 20% X6S  pkg C0201  page 275 : 1 = P5E_CPU0_P0_TX_BUF_C_DN<3> ; 2 = P5E_CPU0_P0_TX_BUF_DN<3>
C6509  Q_CAP_DIFFBUS  DIFF BUS_0.22UF 6.3V 20% X6S  pkg C0201  page 275 : 1 = P5E_CPU0_P0_TX_BUF_C_DP<4> ; 2 = P5E_CPU0_P0_TX_BUF_DP<4>
C6510  Q_CAP_DIFFBUS  DIFF BUS_0.22UF 6.3V 20% X6S  pkg C0201  page 275 : 1 = P5E_CPU0_P0_TX_BUF_C_DN<4> ; 2 = P5E_CPU0_P0_TX_BUF_DN<4>
C6511  Q_CAP_DIFFBUS  DIFF BUS_0.22UF 6.3V 20% X6S  pkg C0201  page 275 : 1 = P5E_CPU0_P0_TX_BUF_C_DP<5> ; 2 = P5E_CPU0_P0_TX_BUF_DP<5>
C6512  Q_CAP_DIFFBUS  DIFF BUS_0.22UF 6.3V 20% X6S  pkg C0201  page 275 : 1 = P5E_CPU0_P0_TX_BUF_C_DN<5> ; 2 = P5E_CPU0_P0_TX_BUF_DN<5>
C6513  Q_CAP_DIFFBUS  DIFF BUS_0.22UF 6.3V 20% X6S  pkg C0201  page 275 : 1 = P5E_CPU0_P0_TX_BUF_C_DP<6> ; 2 = P5E_CPU0_P0_TX_BUF_DP<6>
C6514  Q_CAP_DIFFBUS  DIFF BUS_0.22UF 6.3V 20% X6S  pkg C0201  page 275 : 1 = P5E_CPU0_P0_TX_BUF_C_DN<6> ; 2 = P5E_CPU0_P0_TX_BUF_DN<6>
C6515  Q_CAP_DIFFBUS  DIFF BUS_0.22UF 6.3V 20% X6S  pkg C0201  page 275 : 1 = P5E_CPU0_P0_TX_BUF_C_DP<7> ; 2 = P5E_CPU0_P0_TX_BUF_DP<7>
C6516  Q_CAP_DIFFBUS  DIFF BUS_0.22UF 6.3V 20% X6S  pkg C0201  page 275 : 1 = P5E_CPU0_P0_TX_BUF_C_DN<7> ; 2 = P5E_CPU0_P0_TX_BUF_DN<7>
C6517  Q_CAP_DIFFBUS  DIFF BUS_0.22UF 6.3V 20% X6S  pkg C0201  page 275 : 1 = P5E_CPU0_P0_TX_BUF_C_DP<8> ; 2 = P5E_CPU0_P0_TX_BUF_DP<8>
C6518  Q_CAP_DIFFBUS  DIFF BUS_0.22UF 6.3V 20% X6S  pkg C0201  page 275 : 1 = P5E_CPU0_P0_TX_BUF_C_DN<8> ; 2 = P5E_CPU0_P0_TX_BUF_DN<8>
C6519  Q_CAP_DIFFBUS  DIFF BUS_0.22UF 6.3V 20% X6S  pkg C0201  page 275 : 1 = P5E_CPU0_P0_TX_BUF_C_DP<9> ; 2 = P5E_CPU0_P0_TX_BUF_DP<9>
C6520  Q_CAP_DIFFBUS  DIFF BUS_0.22UF 6.3V 20% X6S  pkg C0201  page 275 : 1 = P5E_CPU0_P0_TX_BUF_C_DN<9> ; 2 = P5E_CPU0_P0_TX_BUF_DN<9>
C6521  Q_CAP_DIFFBUS  DIFF BUS_0.22UF 6.3V 20% X6S  pkg C0201  page 275 : 1 = P5E_CPU0_P0_TX_BUF_C_DP<10> ; 2 = P5E_CPU0_P0_TX_BUF_DP<10>
C6522  Q_CAP_DIFFBUS  DIFF BUS_0.22UF 6.3V 20% X6S  pkg C0201  page 275 : 1 = P5E_CPU0_P0_TX_BUF_C_DN<10> ; 2 = P5E_CPU0_P0_TX_BUF_DN<10>
C6523  Q_CAP_DIFFBUS  DIFF BUS_0.22UF 6.3V 20% X6S  pkg C0201  page 275 : 1 = P5E_CPU0_P0_TX_BUF_C_DP<11> ; 2 = P5E_CPU0_P0_TX_BUF_DP<11>
C6524  Q_CAP_DIFFBUS  DIFF BUS_0.22UF 6.3V 20% X6S  pkg C0201  page 275 : 1 = P5E_CPU0_P0_TX_BUF_C_DN<11> ; 2 = P5E_CPU0_P0_TX_BUF_DN<11>
C6525  Q_CAP_DIFFBUS  DIFF BUS_0.22UF 6.3V 20% X6S  pkg C0201  page 275 : 1 = P5E_CPU0_P0_TX_BUF_C_DP<12> ; 2 = P5E_CPU0_P0_TX_BUF_DP<12>
C6526  Q_CAP_DIFFBUS  DIFF BUS_0.22UF 6.3V 20% X6S  pkg C0201  page 275 : 1 = P5E_CPU0_P0_TX_BUF_C_DN<12> ; 2 = P5E_CPU0_P0_TX_BUF_DN<12>
C6527  Q_CAP_DIFFBUS  DIFF BUS_0.22UF 6.3V 20% X6S  pkg C0201  page 275 : 1 = P5E_CPU0_P0_TX_BUF_C_DP<13> ; 2 = P5E_CPU0_P0_TX_BUF_DP<13>
C6528  Q_CAP_DIFFBUS  DIFF BUS_0.22UF 6.3V 20% X6S  pkg C0201  page 275 : 1 = P5E_CPU0_P0_TX_BUF_C_DN<13> ; 2 = P5E_CPU0_P0_TX_BUF_DN<13>
C6529  Q_CAP_DIFFBUS  DIFF BUS_0.22UF 6.3V 20% X6S  pkg C0201  page 275 : 1 = P5E_CPU0_P0_TX_BUF_C_DP<14> ; 2 = P5E_CPU0_P0_TX_BUF_DP<14>
C6530  Q_CAP_DIFFBUS  DIFF BUS_0.22UF 6.3V 20% X6S  pkg C0201  page 275 : 1 = P5E_CPU0_P0_TX_BUF_C_DN<14> ; 2 = P5E_CPU0_P0_TX_BUF_DN<14>
C6531  Q_CAP_DIFFBUS  DIFF BUS_0.22UF 6.3V 20% X6S  pkg C0201  page 275 : 1 = P5E_CPU0_P0_TX_BUF_C_DP<15> ; 2 = P5E_CPU0_P0_TX_BUF_DP<15>
C6532  Q_CAP_DIFFBUS  DIFF BUS_0.22UF 6.3V 20% X6S  pkg C0201  page 275 : 1 = P5E_CPU0_P0_TX_BUF_C_DN<15> ; 2 = P5E_CPU0_P0_TX_BUF_DN<15>
C6533  Q_CAP_DIFFBUS  DIFF BUS_0.22UF 6.3V 20% X6S  pkg C0201  page 286 : 1 = P5E_CPU0_P1_TX_BUF_C_DP<0> ; 2 = P5E_CPU0_P1_TX_BUF_DP<0>
C6534  Q_CAP_DIFFBUS  DIFF BUS_0.22UF 6.3V 20% X6S  pkg C0201  page 286 : 1 = P5E_CPU0_P1_TX_BUF_C_DN<0> ; 2 = P5E_CPU0_P1_TX_BUF_DN<0>
C6535  Q_CAP_DIFFBUS  DIFF BUS_0.22UF 6.3V 20% X6S  pkg C0201  page 286 : 1 = P5E_CPU0_P1_TX_BUF_C_DP<1> ; 2 = P5E_CPU0_P1_TX_BUF_DP<1>
C6536  Q_CAP_DIFFBUS  DIFF BUS_0.22UF 6.3V 20% X6S  pkg C0201  page 286 : 1 = P5E_CPU0_P1_TX_BUF_C_DN<1> ; 2 = P5E_CPU0_P1_TX_BUF_DN<1>
C6537  Q_CAP_DIFFBUS  DIFF BUS_0.22UF 6.3V 20% X6S  pkg C0201  page 286 : 1 = P5E_CPU0_P1_TX_BUF_C_DP<2> ; 2 = P5E_CPU0_P1_TX_BUF_DP<2>
C6538  Q_CAP_DIFFBUS  DIFF BUS_0.22UF 6.3V 20% X6S  pkg C0201  page 286 : 1 = P5E_CPU0_P1_TX_BUF_C_DN<2> ; 2 = P5E_CPU0_P1_TX_BUF_DN<2>
C6539  Q_CAP_DIFFBUS  DIFF BUS_0.22UF 6.3V 20% X6S  pkg C0201  page 286 : 1 = P5E_CPU0_P1_TX_BUF_C_DP<3> ; 2 = P5E_CPU0_P1_TX_BUF_DP<3>
C6540  Q_CAP_DIFFBUS  DIFF BUS_0.22UF 6.3V 20% X6S  pkg C0201  page 286 : 1 = P5E_CPU0_P1_TX_BUF_C_DN<3> ; 2 = P5E_CPU0_P1_TX_BUF_DN<3>
C6541  Q_CAP_DIFFBUS  DIFF BUS_0.22UF 6.3V 20% X6S  pkg C0201  page 286 : 1 = P5E_CPU0_P1_TX_BUF_C_DP<4> ; 2 = P5E_CPU0_P1_TX_BUF_DP<4>
C6542  Q_CAP_DIFFBUS  DIFF BUS_0.22UF 6.3V 20% X6S  pkg C0201  page 286 : 1 = P5E_CPU0_P1_TX_BUF_C_DN<4> ; 2 = P5E_CPU0_P1_TX_BUF_DN<4>
C6543  Q_CAP_DIFFBUS  DIFF BUS_0.22UF 6.3V 20% X6S  pkg C0201  page 286 : 1 = P5E_CPU0_P1_TX_BUF_C_DP<5> ; 2 = P5E_CPU0_P1_TX_BUF_DP<5>
C6544  Q_CAP_DIFFBUS  DIFF BUS_0.22UF 6.3V 20% X6S  pkg C0201  page 286 : 1 = P5E_CPU0_P1_TX_BUF_C_DN<5> ; 2 = P5E_CPU0_P1_TX_BUF_DN<5>
C6545  Q_CAP_DIFFBUS  DIFF BUS_0.22UF 6.3V 20% X6S  pkg C0201  page 286 : 1 = P5E_CPU0_P1_TX_BUF_C_DP<6> ; 2 = P5E_CPU0_P1_TX_BUF_DP<6>
C6546  Q_CAP_DIFFBUS  DIFF BUS_0.22UF 6.3V 20% X6S  pkg C0201  page 286 : 1 = P5E_CPU0_P1_TX_BUF_C_DN<6> ; 2 = P5E_CPU0_P1_TX_BUF_DN<6>
C6547  Q_CAP_DIFFBUS  DIFF BUS_0.22UF 6.3V 20% X6S  pkg C0201  page 286 : 1 = P5E_CPU0_P1_TX_BUF_C_DP<7> ; 2 = P5E_CPU0_P1_TX_BUF_DP<7>
C6548  Q_CAP_DIFFBUS  DIFF BUS_0.22UF 6.3V 20% X6S  pkg C0201  page 286 : 1 = P5E_CPU0_P1_TX_BUF_C_DN<7> ; 2 = P5E_CPU0_P1_TX_BUF_DN<7>
C6549  Q_CAP_DIFFBUS  DIFF BUS_0.22UF 6.3V 20% X6S  pkg C0201  page 286 : 1 = P5E_CPU0_P1_TX_BUF_C_DP<8> ; 2 = P5E_CPU0_P1_TX_BUF_DP<8>
C6550  Q_CAP_DIFFBUS  DIFF BUS_0.22UF 6.3V 20% X6S  pkg C0201  page 286 : 1 = P5E_CPU0_P1_TX_BUF_C_DN<8> ; 2 = P5E_CPU0_P1_TX_BUF_DN<8>
C6551  Q_CAP_DIFFBUS  DIFF BUS_0.22UF 6.3V 20% X6S  pkg C0201  page 286 : 1 = P5E_CPU0_P1_TX_BUF_C_DP<9> ; 2 = P5E_CPU0_P1_TX_BUF_DP<9>
C6552  Q_CAP_DIFFBUS  DIFF BUS_0.22UF 6.3V 20% X6S  pkg C0201  page 286 : 1 = P5E_CPU0_P1_TX_BUF_C_DN<9> ; 2 = P5E_CPU0_P1_TX_BUF_DN<9>
C6553  Q_CAP_DIFFBUS  DIFF BUS_0.22UF 6.3V 20% X6S  pkg C0201  page 286 : 1 = P5E_CPU0_P1_TX_BUF_C_DP<10> ; 2 = P5E_CPU0_P1_TX_BUF_DP<10>
C6554  Q_CAP_DIFFBUS  DIFF BUS_0.22UF 6.3V 20% X6S  pkg C0201  page 286 : 1 = P5E_CPU0_P1_TX_BUF_C_DN<10> ; 2 = P5E_CPU0_P1_TX_BUF_DN<10>
C6555  Q_CAP_DIFFBUS  DIFF BUS_0.22UF 6.3V 20% X6S  pkg C0201  page 286 : 1 = P5E_CPU0_P1_TX_BUF_C_DP<11> ; 2 = P5E_CPU0_P1_TX_BUF_DP<11>
C6556  Q_CAP_DIFFBUS  DIFF BUS_0.22UF 6.3V 20% X6S  pkg C0201  page 286 : 1 = P5E_CPU0_P1_TX_BUF_C_DN<11> ; 2 = P5E_CPU0_P1_TX_BUF_DN<11>
C6557  Q_CAP_DIFFBUS  DIFF BUS_0.22UF 6.3V 20% X6S  pkg C0201  page 286 : 1 = P5E_CPU0_P1_TX_BUF_C_DP<12> ; 2 = P5E_CPU0_P1_TX_BUF_DP<12>
C6558  Q_CAP_DIFFBUS  DIFF BUS_0.22UF 6.3V 20% X6S  pkg C0201  page 286 : 1 = P5E_CPU0_P1_TX_BUF_C_DN<12> ; 2 = P5E_CPU0_P1_TX_BUF_DN<12>
C6559  Q_CAP_DIFFBUS  DIFF BUS_0.22UF 6.3V 20% X6S  pkg C0201  page 286 : 1 = P5E_CPU0_P1_TX_BUF_C_DP<13> ; 2 = P5E_CPU0_P1_TX_BUF_DP<13>
C6560  Q_CAP_DIFFBUS  DIFF BUS_0.22UF 6.3V 20% X6S  pkg C0201  page 286 : 1 = P5E_CPU0_P1_TX_BUF_C_DN<13> ; 2 = P5E_CPU0_P1_TX_BUF_DN<13>
C6561  Q_CAP_DIFFBUS  DIFF BUS_0.22UF 6.3V 20% X6S  pkg C0201  page 286 : 1 = P5E_CPU0_P1_TX_BUF_C_DP<14> ; 2 = P5E_CPU0_P1_TX_BUF_DP<14>
C6562  Q_CAP_DIFFBUS  DIFF BUS_0.22UF 6.3V 20% X6S  pkg C0201  page 286 : 1 = P5E_CPU0_P1_TX_BUF_C_DN<14> ; 2 = P5E_CPU0_P1_TX_BUF_DN<14>
C6563  Q_CAP_DIFFBUS  DIFF BUS_0.22UF 6.3V 20% X6S  pkg C0201  page 286 : 1 = P5E_CPU0_P1_TX_BUF_C_DP<15> ; 2 = P5E_CPU0_P1_TX_BUF_DP<15>
C6564  Q_CAP_DIFFBUS  DIFF BUS_0.22UF 6.3V 20% X6S  pkg C0201  page 286 : 1 = P5E_CPU0_P1_TX_BUF_C_DN<15> ; 2 = P5E_CPU0_P1_TX_BUF_DN<15>
C6565  Q_CAP_DIFFBUS  DIFF BUS_0.22UF 6.3V 20% X6S  pkg C0201  page 297 : 1 = P5E_CPU0_P2_TX_BUF_C_DP<0> ; 2 = P5E_CPU0_P2_TX_BUF_DP<0>
C6566  Q_CAP_DIFFBUS  DIFF BUS_0.22UF 6.3V 20% X6S  pkg C0201  page 297 : 1 = P5E_CPU0_P2_TX_BUF_C_DN<0> ; 2 = P5E_CPU0_P2_TX_BUF_DN<0>
C6567  Q_CAP_DIFFBUS  DIFF BUS_0.22UF 6.3V 20% X6S  pkg C0201  page 297 : 1 = P5E_CPU0_P2_TX_BUF_C_DP<1> ; 2 = P5E_CPU0_P2_TX_BUF_DP<1>
C6568  Q_CAP_DIFFBUS  DIFF BUS_0.22UF 6.3V 20% X6S  pkg C0201  page 297 : 1 = P5E_CPU0_P2_TX_BUF_C_DN<1> ; 2 = P5E_CPU0_P2_TX_BUF_DN<1>
C6569  Q_CAP_DIFFBUS  DIFF BUS_0.22UF 6.3V 20% X6S  pkg C0201  page 297 : 1 = P5E_CPU0_P2_TX_BUF_C_DP<2> ; 2 = P5E_CPU0_P2_TX_BUF_DP<2>
C6570  Q_CAP_DIFFBUS  DIFF BUS_0.22UF 6.3V 20% X6S  pkg C0201  page 297 : 1 = P5E_CPU0_P2_TX_BUF_C_DN<2> ; 2 = P5E_CPU0_P2_TX_BUF_DN<2>
C6571  Q_CAP_DIFFBUS  DIFF BUS_0.22UF 6.3V 20% X6S  pkg C0201  page 297 : 1 = P5E_CPU0_P2_TX_BUF_C_DP<3> ; 2 = P5E_CPU0_P2_TX_BUF_DP<3>
